# S9S_MB_2U (Grand Teton) — schematic netlist excerpt (pin names and nets, part order shuffled) for the footprints in the layout excerpt that follows; sources: Cadence DE-HDL packaged netlist, KiCad conversion of 03242023_DA0F0TMBIJ0_F0T_Motherboard_J_brd_V01_OCP.brd

X29  TP_TDR_4P_FTS  TP_TDR_4P_DIP EMPTY  pkg TH  page 309
  S1  = TDR_DIFF_100_IN5_DP
  P1  = T1_GND
  P2  = T1_GND
  S2  = TDR_DIFF_100_IN5_DN

R4388  Q_RES  150 1% CHIP  pkg 0402LF  page 225 : A = PVNN_TERM_CPU0 ; B = H_CPU_ERR1_LVC1_R_N

(kicad_pcb
	(version 20260206)
	(generator "pcbnew")
	(generator_version "10.0")
	(general
		(thickness 1.6)
		(legacy_teardrops no)
	)
	(paper "A4")
	(title_block
		(title "03242023_DA0F0TMBIJ0_F0T_Motherboard_J_brd_V01_OCP.brd")
		(comment 1 "Grand Teton / footprints 5378-5379 of 6105")
	)
	(layers
		(0 "F.Cu" signal "TOP")
		(4 "In1.Cu" signal "GND")
		(6 "In2.Cu" signal "IN1")
		(8 "In3.Cu" signal "GND1")
		(10 "In4.Cu" signal "IN2")
		(12 "In5.Cu" signal "GND2")
		(14 "In6.Cu" signal "IN3")
		(16 "In7.Cu" signal "GND3")
		(18 "In8.Cu" signal "VCC")
		(20 "In9.Cu" signal "VCC1")
		(22 "In10.Cu" signal "GND4")
		(24 "In11.Cu" signal "IN4")
		(26 "In12.Cu" signal "GND5")
		(28 "In13.Cu" signal "IN5")
		(30 "In14.Cu" signal "GND6")
		(32 "In15.Cu" signal "IN6")
		(34 "In16.Cu" signal "GND7")
		(2 "B.Cu" signal "BOTTOM")
		(9 "F.Adhes" user "F.Adhesive")
		(11 "B.Adhes" user "B.Adhesive")
		(13 "F.Paste" user "Package Geometry/Pastemask Top")
		(15 "B.Paste" user "Package Geometry/Pastemask Bottom")
		(5 "F.SilkS" user "Ref Des/Silkscreen Top")
		(7 "B.SilkS" user "Ref Des/Silkscreen Bottom")
		(1 "F.Mask" user "Board Geometry/Soldermask Top")
		(3 "B.Mask" user "Board Geometry/Soldermask Bottom")
		(17 "Dwgs.User" user "User.Drawings")
		(19 "Cmts.User" user "User.Comments")
		(21 "Eco1.User" user "User.Eco1")
		(23 "Eco2.User" user "User.Eco2")
		(25 "Edge.Cuts" user "Board Geometry/Outline")
		(27 "Margin" user)
		(31 "F.CrtYd" user "Package Geometry/Place Bound Top")
		(29 "B.CrtYd" user "Package Geometry/Place Bound Bottom")
		(35 "F.Fab" user "Ref Des/Assembly Top")
		(33 "B.Fab" user "Ref Des/Assembly Bottom")
	)
	(footprint ""
		(layer "B.Cu")
		(at 506.598428 -148.08708 -90)
		(property "Reference" "X29"
			(at 3.734816 3.412998 270)
			(unlocked yes)
			(layer "B.SilkS")
			(effects
				(font
					(size 0.7874 0.5842)
					(thickness 0.1524)
				)
				(justify left mirror)
			)
		)
		(property "Value" ""
			(at 0 0 90)
			(layer "B.Fab")
			(effects
				(font
					(size 1.27 1.27)
				)
				(justify mirror)
			)
		)
		(property "Device Type" "TP_TDR_4P_FTS_TH-TP_TDR_4P_DIPA"
			(at -1.30175 1.27 180)
			(unlocked yes)
			(layer "B.Fab")
			(hide yes)
			(effects
				(font
					(size 0.635 0.4064)
					(thickness 0.1524)
				)
				(justify mirror)
			)
		)
		(property "User Part Number" "N_A"
			(at -1.30175 1.27 180)
			(unlocked yes)
			(layer "Cmts.User")
			(hide yes)
			(effects
				(font
					(size 0.635 0.4064)
					(thickness 0.1524)
				)
				(justify mirror)
			)
		)
		(duplicate_pad_numbers_are_jumpers no)
		(fp_line
			(start -2.54 3.81)
			(end -2.54 3.6703)
			(stroke
				(width 0.1524)
				(type default)
			)
			(layer "B.SilkS")
		)
		(fp_line
			(start 0 3.81)
			(end -2.54 3.81)
			(stroke
				(width 0.1524)
				(type default)
			)
			(layer "B.SilkS")
		)
		(fp_line
			(start 0 3.175)
			(end 0 3.81)
			(stroke
				(width 0.1524)
				(type default)
			)
			(layer "B.SilkS")
		)
		(fp_line
			(start -2.54 1.4097)
			(end -2.54 1.1303)
			(stroke
				(width 0.1524)
				(type default)
			)
			(layer "B.SilkS")
		)
		(fp_line
			(start 0 0.635)
			(end 0 1.905)
			(stroke
				(width 0.1524)
				(type default)
			)
			(layer "B.SilkS")
		)
		(fp_line
			(start -2.54 -1.1303)
			(end -2.54 -1.27)
			(stroke
				(width 0.1524)
				(type default)
			)
			(layer "B.SilkS")
		)
		(fp_line
			(start -2.54 -1.27)
			(end 0 -1.27)
			(stroke
				(width 0.1524)
				(type default)
			)
			(layer "B.SilkS")
		)
		(fp_line
			(start 0 -1.27)
			(end 0 -0.635)
			(stroke
				(width 0.1524)
				(type default)
			)
			(layer "B.SilkS")
		)
		(fp_poly
			(pts
				(xy 2.938526 -0.71882) (xy 2.938526 0.80518) (xy 1.414526 0.04318)
			)
			(stroke
				(width 0)
				(type default)
			)
			(fill yes)
			(layer "B.SilkS")
		)
		(fp_line
			(start -2.54 3.81)
			(end -2.54 -1.27)
			(stroke
				(width 0.1)
				(type default)
			)
			(layer "B.Fab")
		)
		(fp_line
			(start 0 3.81)
			(end -2.54 3.81)
			(stroke
				(width 0.1)
				(type default)
			)
			(layer "B.Fab")
		)
		(fp_line
			(start -2.54 -1.27)
			(end 0 -1.27)
			(stroke
				(width 0.1)
				(type default)
			)
			(layer "B.Fab")
		)
		(fp_line
			(start 0 -1.27)
			(end 0 3.81)
			(stroke
				(width 0.1)
				(type default)
			)
			(layer "B.Fab")
		)
		(fp_poly
			(pts
				(xy 0.761746 0) (xy 2.285746 -0.762) (xy 2.285746 0.762)
			)
			(stroke
				(width 0)
				(type default)
			)
			(fill yes)
			(layer "B.Fab")
		)
		(pad "1" thru_hole circle
			(at 0 0 90)
			(size 1.0033 1.0033)
			(drill 0.249936)
			(layers "*.Cu" "*.Mask")
			(remove_unused_layers no)
			(net "TDR_DIFF_100_IN5_DP")
			(clearance 0.10795)
			(padstack
				(mode front_inner_back)
				(layer "Inner"
					(shape circle)
					(size 0.8001 0.8001)
					(clearance 0.1524)
				)
				(layer "B.Cu"
					(shape circle)
					(size 1.0033 1.0033)
					(thermal_gap 0.10795)
					(clearance 0.10795)
				)
			)
		)
		(pad "2" thru_hole circle
			(at -2.54 0 90)
			(size 1.9939 1.9939)
			(drill 0.249936)
			(layers "*.Cu" "*.Mask")
			(remove_unused_layers no)
			(net "T1_GND")
			(clearance 0.10795)
			(padstack
				(mode front_inner_back)
				(layer "Inner"
					(shape circle)
					(size 0.8001 0.8001)
					(clearance 0.1524)
				)
				(layer "B.Cu"
					(shape circle)
					(size 1.9939 1.9939)
					(thermal_gap 0.10795)
					(clearance 0.10795)
				)
			)
		)
		(pad "3" thru_hole circle
			(at -2.54 2.54 90)
			(size 1.9939 1.9939)
			(drill 0.249936)
			(layers "*.Cu" "*.Mask")
			(remove_unused_layers no)
			(net "T1_GND")
			(clearance 0.10795)
			(padstack
				(mode front_inner_back)
				(layer "Inner"
					(shape circle)
					(size 0.8001 0.8001)
					(clearance 0.1524)
				)
				(layer "B.Cu"
					(shape circle)
					(size 1.9939 1.9939)
					(thermal_gap 0.10795)
					(clearance 0.10795)
				)
			)
		)
		(pad "4" thru_hole circle
			(at 0 2.54 90)
			(size 1.0033 1.0033)
			(drill 0.249936)
			(layers "*.Cu" "*.Mask")
			(remove_unused_layers no)
			(net "TDR_DIFF_100_IN5_DN")
			(clearance 0.10795)
			(padstack
				(mode front_inner_back)
				(layer "Inner"
					(shape circle)
					(size 0.8001 0.8001)
					(clearance 0.1524)
				)
				(layer "B.Cu"
					(shape circle)
					(size 1.0033 1.0033)
					(thermal_gap 0.10795)
					(clearance 0.10795)
				)
			)
		)
	)
	(footprint ""
		(layer "B.Cu")
		(at 315.569092 -191.215518 90)
		(property "Reference" "R4388"
			(at 0 0 90)
			(layer "B.SilkS")
			(hide yes)
			(effects
				(font
					(size 1.27 1.27)
				)
				(justify mirror)
			)
		)
		(property "Value" ""
			(at 0 0 90)
			(layer "B.Fab")
			(effects
				(font
					(size 1.27 1.27)
				)
				(justify mirror)
			)
		)
		(duplicate_pad_numbers_are_jumpers no)
		(fp_line
			(start 0.7874 -0.4064)
			(end -0.7874 -0.4064)
			(stroke
				(width 0.1524)
				(type default)
			)
			(layer "B.SilkS")
		)
		(fp_line
			(start -0.7874 -0.4064)
			(end -0.7874 0.4064)
			(stroke
				(width 0.1524)
				(type default)
			)
			(layer "B.SilkS")
		)
		(fp_line
			(start 0.7874 0.4064)
			(end 0.7874 -0.4064)
			(stroke
				(width 0.1524)
				(type default)
			)
			(layer "B.SilkS")
		)
		(fp_line
			(start -0.7874 0.4064)
			(end 0.7874 0.4064)
			(stroke
				(width 0.1524)
				(type default)
			)
			(layer "B.SilkS")
		)
		(fp_line
			(start 0.67945 -0.305054)
			(end 0.12065 -0.305054)
			(stroke
				(width 0.1)
				(type default)
			)
			(layer "B.Fab")
		)
		(fp_line
			(start 0.12065 -0.305054)
			(end 0.12065 -0.2794)
			(stroke
				(width 0.1)
				(type default)
			)
			(layer "B.Fab")
		)
		(fp_line
			(start -0.12065 -0.3048)
			(end -0.67945 -0.3048)
			(stroke
				(width 0.1)
				(type default)
			)
			(layer "B.Fab")
		)
		(fp_line
			(start -0.67945 -0.3048)
			(end -0.67945 0.3048)
			(stroke
				(width 0.1)
				(type default)
			)
			(layer "B.Fab")
		)
		(fp_line
			(start 0.12065 -0.2794)
			(end -0.12065 -0.2794)
			(stroke
				(width 0.1)
				(type default)
			)
			(layer "B.Fab")
		)
		(fp_line
			(start -0.12065 -0.2794)
			(end -0.12065 -0.3048)
			(stroke
				(width 0.1)
				(type default)
			)
			(layer "B.Fab")
		)
		(fp_line
			(start 0.12065 0.2794)
			(end 0.12065 0.3048)
			(stroke
				(width 0.1)
				(type default)
			)
			(layer "B.Fab")
		)
		(fp_line
			(start -0.120396 0.2794)
			(end 0.12065 0.2794)
			(stroke
				(width 0.1)
				(type default)
			)
			(layer "B.Fab")
		)
		(fp_line
			(start 0.67945 0.3048)
			(end 0.67945 -0.305054)
			(stroke
				(width 0.1)
				(type default)
			)
			(layer "B.Fab")
		)
		(fp_line
			(start 0.12065 0.3048)
			(end 0.67945 0.3048)
			(stroke
				(width 0.1)
				(type default)
			)
			(layer "B.Fab")
		)
		(fp_line
			(start -0.120396 0.3048)
			(end -0.120396 0.2794)
			(stroke
				(width 0.1)
				(type default)
			)
			(layer "B.Fab")
		)
		(fp_line
			(start -0.67945 0.3048)
			(end -0.120396 0.3048)
			(stroke
				(width 0.1)
				(type default)
			)
			(layer "B.Fab")
		)
		(pad "1" smd circle
			(at 0.40005 0 270)
			(size 0 0)
			(layers "B.Cu" "B.Mask" "B.Paste")
			(net "PVNN_TERM_CPU0")
		)
		(pad "2" smd circle
			(at -0.40005 0 270)
			(size 0 0)
			(layers "B.Cu" "B.Mask" "B.Paste")
			(net "H_CPU_ERR1_LVC1_R_N")
		)
	)
)
